# S9S_MB_2U (Grand Teton) — schematic netlist excerpt (pin names and nets, part order shuffled) for the footprints in the layout excerpt that follows; sources: Cadence DE-HDL packaged netlist, KiCad conversion of 03242023_DA0F0TMBIJ0_F0T_Motherboard_J_brd_V01_OCP.brd

R3238  Q_RES  33.2 1% CHIP  pkg 0402LF  page 240 : A = SMB_OCP_SFF_3V3AUX_SCL ; B = SMB_OCP_SFF_3V3AUX_SCL_R0
PR157  Q_RES  0 5% EMPTY  pkg 0402LF  page 266 : A = P12V_AUX ; B = PVCCIN_CPU0_CSPIN
C391  Q_CAP  47UF 4V 20% X6S  pkg C0805  page 75 : A = PVCCIN_CPU0 ; B = GND

(kicad_pcb
	(version 20260206)
	(generator "pcbnew")
	(generator_version "10.0")
	(general
		(thickness 1.6)
		(legacy_teardrops no)
	)
	(paper "A4")
	(title_block
		(title "03242023_DA0F0TMBIJ0_F0T_Motherboard_J_brd_V01_OCP.brd")
		(comment 1 "Grand Teton / footprints 4488-4490 of 6105")
	)
	(layers
		(0 "F.Cu" signal "TOP")
		(4 "In1.Cu" signal "GND")
		(6 "In2.Cu" signal "IN1")
		(8 "In3.Cu" signal "GND1")
		(10 "In4.Cu" signal "IN2")
		(12 "In5.Cu" signal "GND2")
		(14 "In6.Cu" signal "IN3")
		(16 "In7.Cu" signal "GND3")
		(18 "In8.Cu" signal "VCC")
		(20 "In9.Cu" signal "VCC1")
		(22 "In10.Cu" signal "GND4")
		(24 "In11.Cu" signal "IN4")
		(26 "In12.Cu" signal "GND5")
		(28 "In13.Cu" signal "IN5")
		(30 "In14.Cu" signal "GND6")
		(32 "In15.Cu" signal "IN6")
		(34 "In16.Cu" signal "GND7")
		(2 "B.Cu" signal "BOTTOM")
		(9 "F.Adhes" user "F.Adhesive")
		(11 "B.Adhes" user "B.Adhesive")
		(13 "F.Paste" user "Package Geometry/Pastemask Top")
		(15 "B.Paste" user "Package Geometry/Pastemask Bottom")
		(5 "F.SilkS" user "Ref Des/Silkscreen Top")
		(7 "B.SilkS" user "Ref Des/Silkscreen Bottom")
		(1 "F.Mask" user "Board Geometry/Soldermask Top")
		(3 "B.Mask" user "Board Geometry/Soldermask Bottom")
		(17 "Dwgs.User" user "User.Drawings")
		(19 "Cmts.User" user "User.Comments")
		(21 "Eco1.User" user "User.Eco1")
		(23 "Eco2.User" user "User.Eco2")
		(25 "Edge.Cuts" user "Board Geometry/Outline")
		(27 "Margin" user)
		(31 "F.CrtYd" user "Package Geometry/Place Bound Top")
		(29 "B.CrtYd" user "Package Geometry/Place Bound Bottom")
		(35 "F.Fab" user "Ref Des/Assembly Top")
		(33 "B.Fab" user "Ref Des/Assembly Bottom")
	)
	(footprint ""
		(layer "B.Cu")
		(at 353.619308 -244.820186 -90)
		(property "Reference" "C391"
			(at 0 0 90)
			(layer "B.SilkS")
			(hide yes)
			(effects
				(font
					(size 1.27 1.27)
				)
				(justify mirror)
			)
		)
		(property "Value" ""
			(at 0 0 90)
			(layer "B.Fab")
			(effects
				(font
					(size 1.27 1.27)
				)
				(justify mirror)
			)
		)
		(duplicate_pad_numbers_are_jumpers no)
		(fp_line
			(start -1.524 0.762)
			(end 1.524 0.762)
			(stroke
				(width 0.1524)
				(type default)
			)
			(layer "B.SilkS")
		)
		(fp_line
			(start 1.524 0.762)
			(end 1.524 -0.762)
			(stroke
				(width 0.1524)
				(type default)
			)
			(layer "B.SilkS")
		)
		(fp_line
			(start -1.524 -0.762)
			(end -1.524 0.762)
			(stroke
				(width 0.1524)
				(type default)
			)
			(layer "B.SilkS")
		)
		(fp_line
			(start 1.524 -0.762)
			(end -1.524 -0.762)
			(stroke
				(width 0.1524)
				(type default)
			)
			(layer "B.SilkS")
		)
		(fp_line
			(start -1.1049 0.724916)
			(end -1.1049 -0.724916)
			(stroke
				(width 0.1)
				(type default)
			)
			(layer "B.Fab")
		)
		(fp_line
			(start 1.1049 0.724916)
			(end -1.1049 0.724916)
			(stroke
				(width 0.1)
				(type default)
			)
			(layer "B.Fab")
		)
		(fp_line
			(start -1.1049 -0.724916)
			(end 1.1049 -0.724916)
			(stroke
				(width 0.1)
				(type default)
			)
			(layer "B.Fab")
		)
		(fp_line
			(start 1.1049 -0.724916)
			(end 1.1049 0.724916)
			(stroke
				(width 0.1)
				(type default)
			)
			(layer "B.Fab")
		)
		(pad "1" smd rect
			(at 0.889 0 270)
			(size 1.016 1.27)
			(layers "B.Cu" "B.Mask" "B.Paste")
			(net "PVCCIN_CPU0")
		)
		(pad "2" smd rect
			(at -0.889 0 270)
			(size 1.016 1.27)
			(layers "B.Cu" "B.Mask" "B.Paste")
			(net "GND")
		)
	)
	(footprint ""
		(layer "B.Cu")
		(at 362.31449 -360.418126 -90)
		(property "Reference" "PR157"
			(at 0 0 90)
			(layer "B.SilkS")
			(hide yes)
			(effects
				(font
					(size 1.27 1.27)
				)
				(justify mirror)
			)
		)
		(property "Value" ""
			(at 0 0 90)
			(layer "B.Fab")
			(effects
				(font
					(size 1.27 1.27)
				)
				(justify mirror)
			)
		)
		(duplicate_pad_numbers_are_jumpers no)
		(fp_line
			(start -0.7874 0.4064)
			(end 0.7874 0.4064)
			(stroke
				(width 0.1524)
				(type default)
			)
			(layer "B.SilkS")
		)
		(fp_line
			(start 0.7874 0.4064)
			(end 0.7874 -0.4064)
			(stroke
				(width 0.1524)
				(type default)
			)
			(layer "B.SilkS")
		)
		(fp_line
			(start -0.7874 -0.4064)
			(end -0.7874 0.4064)
			(stroke
				(width 0.1524)
				(type default)
			)
			(layer "B.SilkS")
		)
		(fp_line
			(start 0.7874 -0.4064)
			(end -0.7874 -0.4064)
			(stroke
				(width 0.1524)
				(type default)
			)
			(layer "B.SilkS")
		)
		(fp_line
			(start -0.67945 0.3048)
			(end -0.120396 0.3048)
			(stroke
				(width 0.1)
				(type default)
			)
			(layer "B.Fab")
		)
		(fp_line
			(start -0.120396 0.3048)
			(end -0.120396 0.2794)
			(stroke
				(width 0.1)
				(type default)
			)
			(layer "B.Fab")
		)
		(fp_line
			(start 0.12065 0.3048)
			(end 0.67945 0.3048)
			(stroke
				(width 0.1)
				(type default)
			)
			(layer "B.Fab")
		)
		(fp_line
			(start 0.67945 0.3048)
			(end 0.67945 -0.305054)
			(stroke
				(width 0.1)
				(type default)
			)
			(layer "B.Fab")
		)
		(fp_line
			(start -0.120396 0.2794)
			(end 0.12065 0.2794)
			(stroke
				(width 0.1)
				(type default)
			)
			(layer "B.Fab")
		)
		(fp_line
			(start 0.12065 0.2794)
			(end 0.12065 0.3048)
			(stroke
				(width 0.1)
				(type default)
			)
			(layer "B.Fab")
		)
		(fp_line
			(start -0.12065 -0.2794)
			(end -0.12065 -0.3048)
			(stroke
				(width 0.1)
				(type default)
			)
			(layer "B.Fab")
		)
		(fp_line
			(start 0.12065 -0.2794)
			(end -0.12065 -0.2794)
			(stroke
				(width 0.1)
				(type default)
			)
			(layer "B.Fab")
		)
		(fp_line
			(start -0.67945 -0.3048)
			(end -0.67945 0.3048)
			(stroke
				(width 0.1)
				(type default)
			)
			(layer "B.Fab")
		)
		(fp_line
			(start -0.12065 -0.3048)
			(end -0.67945 -0.3048)
			(stroke
				(width 0.1)
				(type default)
			)
			(layer "B.Fab")
		)
		(fp_line
			(start 0.12065 -0.305054)
			(end 0.12065 -0.2794)
			(stroke
				(width 0.1)
				(type default)
			)
			(layer "B.Fab")
		)
		(fp_line
			(start 0.67945 -0.305054)
			(end 0.12065 -0.305054)
			(stroke
				(width 0.1)
				(type default)
			)
			(layer "B.Fab")
		)
		(pad "1" smd circle
			(at 0.40005 0 90)
			(size 0 0)
			(layers "B.Cu" "B.Mask" "B.Paste")
			(net "P12V_AUX")
		)
		(pad "2" smd circle
			(at -0.40005 0 90)
			(size 0 0)
			(layers "B.Cu" "B.Mask" "B.Paste")
			(net "PVCCIN_CPU0_CSPIN")
		)
	)
	(footprint ""
		(layer "B.Cu")
		(at 183.885078 -18.710148 90)
		(property "Reference" "R3238"
			(at 0 0 90)
			(layer "B.SilkS")
			(hide yes)
			(effects
				(font
					(size 1.27 1.27)
				)
				(justify mirror)
			)
		)
		(property "Value" ""
			(at 0 0 90)
			(layer "B.Fab")
			(effects
				(font
					(size 1.27 1.27)
				)
				(justify mirror)
			)
		)
		(duplicate_pad_numbers_are_jumpers no)
		(fp_line
			(start 0.7874 -0.4064)
			(end -0.7874 -0.4064)
			(stroke
				(width 0.1524)
				(type default)
			)
			(layer "B.SilkS")
		)
		(fp_line
			(start -0.7874 -0.4064)
			(end -0.7874 0.4064)
			(stroke
				(width 0.1524)
				(type default)
			)
			(layer "B.SilkS")
		)
		(fp_line
			(start 0.7874 0.4064)
			(end 0.7874 -0.4064)
			(stroke
				(width 0.1524)
				(type default)
			)
			(layer "B.SilkS")
		)
		(fp_line
			(start -0.7874 0.4064)
			(end 0.7874 0.4064)
			(stroke
				(width 0.1524)
				(type default)
			)
			(layer "B.SilkS")
		)
		(fp_line
			(start 0.67945 -0.305054)
			(end 0.12065 -0.305054)
			(stroke
				(width 0.1)
				(type default)
			)
			(layer "B.Fab")
		)
		(fp_line
			(start 0.12065 -0.305054)
			(end 0.12065 -0.2794)
			(stroke
				(width 0.1)
				(type default)
			)
			(layer "B.Fab")
		)
		(fp_line
			(start -0.12065 -0.3048)
			(end -0.67945 -0.3048)
			(stroke
				(width 0.1)
				(type default)
			)
			(layer "B.Fab")
		)
		(fp_line
			(start -0.67945 -0.3048)
			(end -0.67945 0.3048)
			(stroke
				(width 0.1)
				(type default)
			)
			(layer "B.Fab")
		)
		(fp_line
			(start 0.12065 -0.2794)
			(end -0.12065 -0.2794)
			(stroke
				(width 0.1)
				(type default)
			)
			(layer "B.Fab")
		)
		(fp_line
			(start -0.12065 -0.2794)
			(end -0.12065 -0.3048)
			(stroke
				(width 0.1)
				(type default)
			)
			(layer "B.Fab")
		)
		(fp_line
			(start 0.12065 0.2794)
			(end 0.12065 0.3048)
			(stroke
				(width 0.1)
				(type default)
			)
			(layer "B.Fab")
		)
		(fp_line
			(start -0.120396 0.2794)
			(end 0.12065 0.2794)
			(stroke
				(width 0.1)
				(type default)
			)
			(layer "B.Fab")
		)
		(fp_line
			(start 0.67945 0.3048)
			(end 0.67945 -0.305054)
			(stroke
				(width 0.1)
				(type default)
			)
			(layer "B.Fab")
		)
		(fp_line
			(start 0.12065 0.3048)
			(end 0.67945 0.3048)
			(stroke
				(width 0.1)
				(type default)
			)
			(layer "B.Fab")
		)
		(fp_line
			(start -0.120396 0.3048)
			(end -0.120396 0.2794)
			(stroke
				(width 0.1)
				(type default)
			)
			(layer "B.Fab")
		)
		(fp_line
			(start -0.67945 0.3048)
			(end -0.120396 0.3048)
			(stroke
				(width 0.1)
				(type default)
			)
			(layer "B.Fab")
		)
		(pad "1" smd circle
			(at 0.40005 0 270)
			(size 0 0)
			(layers "B.Cu" "B.Mask" "B.Paste")
			(net "SMB_OCP_SFF_3V3AUX_SCL")
		)
		(pad "2" smd circle
			(at -0.40005 0 270)
			(size 0 0)
			(layers "B.Cu" "B.Mask" "B.Paste")
			(net "SMB_OCP_SFF_3V3AUX_SCL_R0")
		)
	)
)
